# BASEBOARD_FAB2 (Tioga Pass) — schematic netlist excerpt (pin names and nets, part order shuffled) for the footprints in the layout excerpt that follows; sources: Cadence DE-HDL packaged netlist, KiCad conversion of Wiwynn_Tioga_Pass_MB.brd

R4G17  RES  10.0K 1% CHIP  pkg 0402  page 229 : A = P3V3 ; B = PWRGD_PVTT_GHJ_CPU1_R
R8B2  RES  1.00K 1% CHIP  pkg 0402  page 112 : A = XDP_TRST_N ; B = GND
R8E33  RES  0.0 5% CHIP  pkg 0402  page 241 : A = PWRGD_P12V_HSC_DLY ; B = VR_P5V_STBY_EN

(kicad_pcb
	(version 20260206)
	(generator "pcbnew")
	(generator_version "10.0")
	(general
		(thickness 1.6)
		(legacy_teardrops no)
	)
	(paper "A4")
	(title_block
		(title "Wiwynn_Tioga_Pass_MB.brd")
		(comment 1 "Tioga Pass / footprints 293-295 of 4770")
	)
	(layers
		(0 "F.Cu" signal "TOP")
		(4 "In1.Cu" signal "L2GND")
		(6 "In2.Cu" signal "L3")
		(8 "In3.Cu" signal "L4GND")
		(10 "In4.Cu" signal "L5")
		(12 "In5.Cu" signal "L6GND")
		(14 "In6.Cu" signal "L7VCC")
		(16 "In7.Cu" signal "L8VCC")
		(18 "In8.Cu" signal "L9GND")
		(20 "In9.Cu" signal "L10")
		(22 "In10.Cu" signal "L11GND")
		(24 "In11.Cu" signal "L12")
		(26 "In12.Cu" signal "L13GND")
		(2 "B.Cu" signal "BOTTOM")
		(9 "F.Adhes" user "F.Adhesive")
		(11 "B.Adhes" user "B.Adhesive")
		(13 "F.Paste" user "Package Geometry/Pastemask Top")
		(15 "B.Paste" user "Package Geometry/Pastemask Bottom")
		(5 "F.SilkS" user "Ref Des/Silkscreen Top")
		(7 "B.SilkS" user "Ref Des/Silkscreen Bottom")
		(1 "F.Mask" user "Board Geometry/Soldermask Top")
		(3 "B.Mask" user "Board Geometry/Soldermask Bottom")
		(17 "Dwgs.User" user "User.Drawings")
		(19 "Cmts.User" user "User.Comments")
		(21 "Eco1.User" user "User.Eco1")
		(23 "Eco2.User" user "User.Eco2")
		(25 "Edge.Cuts" user "Board Geometry/Outline")
		(27 "Margin" user)
		(31 "F.CrtYd" user "Package Geometry/Place Bound Top")
		(29 "B.CrtYd" user "Package Geometry/Place Bound Bottom")
		(35 "F.Fab" user "Ref Des/Assembly Top")
		(33 "B.Fab" user "Ref Des/Assembly Bottom")
	)
	(footprint ""
		(layer "F.Cu")
		(at 396.494 -66.1416 -90)
		(property "Reference" "R8E33"
			(at 0 0 270)
			(layer "F.SilkS")
			(hide yes)
			(effects
				(font
					(size 1.27 1.27)
				)
			)
		)
		(property "Value" ""
			(at 0 0 270)
			(layer "F.Fab")
			(effects
				(font
					(size 1.27 1.27)
				)
			)
		)
		(duplicate_pad_numbers_are_jumpers no)
		(fp_poly
			(pts
				(xy -0.2794 -0.1016) (xy 0.2794 -0.1016) (xy 0.2794 0.9906) (xy -0.2794 0.9906)
			)
			(stroke
				(width 0)
				(type default)
			)
			(fill no)
			(layer "F.CrtYd")
		)
		(fp_line
			(start -0.2794 0.9906)
			(end 0.2794 0.9906)
			(stroke
				(width 0.1)
				(type default)
			)
			(layer "F.Fab")
		)
		(fp_line
			(start 0.2794 0.9906)
			(end 0.2794 -0.1016)
			(stroke
				(width 0.1)
				(type default)
			)
			(layer "F.Fab")
		)
		(fp_line
			(start -0.2794 -0.1016)
			(end -0.2794 0.9906)
			(stroke
				(width 0.1)
				(type default)
			)
			(layer "F.Fab")
		)
		(fp_line
			(start 0.2794 -0.1016)
			(end -0.2794 -0.1016)
			(stroke
				(width 0.1)
				(type default)
			)
			(layer "F.Fab")
		)
		(pad "1" smd rect
			(at 0 0 270)
			(size 0.508 0.508)
			(layers "F.Cu" "F.Mask" "F.Paste")
			(net "PWRGD_P12V_HSC_DLY")
		)
		(pad "2" smd rect
			(at 0 0.889 270)
			(size 0.508 0.508)
			(layers "F.Cu" "F.Mask" "F.Paste")
			(net "VR_P5V_STBY_EN")
		)
		(zone
			(layer "F.Cu")
			(hatch none 0.5)
			(connect_pads
				(clearance 0)
			)
			(min_thickness 0.25)
			(keepout
				(tracks not_allowed)
				(vias allowed)
				(pads allowed)
				(copperpour not_allowed)
				(footprints allowed)
			)
			(placement
				(enabled no)
				(sheetname "")
			)
			(fill
				(thermal_gap 0.5)
				(thermal_bridge_width 0.5)
				(island_removal_mode 0)
			)
			(polygon
				(pts
					(xy 395.859 -66.3956) (xy 395.859 -65.8876) (xy 396.24 -65.8876) (xy 396.24 -66.3956)
				)
			)
		)
		(zone
			(layer "F.Cu")
			(hatch none 0.5)
			(connect_pads
				(clearance 0)
			)
			(min_thickness 0.25)
			(keepout
				(tracks allowed)
				(vias not_allowed)
				(pads allowed)
				(copperpour not_allowed)
				(footprints allowed)
			)
			(placement
				(enabled no)
				(sheetname "")
			)
			(fill
				(thermal_gap 0.5)
				(thermal_bridge_width 0.5)
				(island_removal_mode 0)
			)
			(polygon
				(pts
					(xy 396.24 -66.3956) (xy 396.24 -65.8876) (xy 395.859 -65.8876) (xy 395.859 -66.3956)
				)
			)
		)
	)
	(footprint ""
		(layer "F.Cu")
		(at 174.5996 -5.461 -90)
		(property "Reference" "R4G17"
			(at 0 0 270)
			(layer "F.SilkS")
			(hide yes)
			(effects
				(font
					(size 1.27 1.27)
				)
			)
		)
		(property "Value" ""
			(at 0 0 270)
			(layer "F.Fab")
			(effects
				(font
					(size 1.27 1.27)
				)
			)
		)
		(duplicate_pad_numbers_are_jumpers no)
		(fp_rect
			(start 0.2794 -0.1016)
			(end -0.2794 0.9906)
			(stroke
				(width 0)
				(type default)
			)
			(fill no)
			(layer "F.CrtYd")
		)
		(fp_line
			(start -0.2794 0.9906)
			(end 0.2794 0.9906)
			(stroke
				(width 0.1)
				(type default)
			)
			(layer "F.Fab")
		)
		(fp_line
			(start 0.2794 0.9906)
			(end 0.2794 -0.1016)
			(stroke
				(width 0.1)
				(type default)
			)
			(layer "F.Fab")
		)
		(fp_line
			(start -0.2794 -0.1016)
			(end -0.2794 0.9906)
			(stroke
				(width 0.1)
				(type default)
			)
			(layer "F.Fab")
		)
		(fp_line
			(start 0.2794 -0.1016)
			(end -0.2794 -0.1016)
			(stroke
				(width 0.1)
				(type default)
			)
			(layer "F.Fab")
		)
		(pad "1" smd rect
			(at 0 0 270)
			(size 0.508 0.508)
			(layers "F.Cu" "F.Mask" "F.Paste")
			(net "P3V3")
		)
		(pad "2" smd rect
			(at 0 0.889 270)
			(size 0.508 0.508)
			(layers "F.Cu" "F.Mask" "F.Paste")
			(net "PWRGD_PVTT_GHJ_CPU1_R")
		)
		(zone
			(layer "F.Cu")
			(hatch none 0.5)
			(connect_pads
				(clearance 0)
			)
			(min_thickness 0.25)
			(keepout
				(tracks allowed)
				(vias not_allowed)
				(pads allowed)
				(copperpour not_allowed)
				(footprints allowed)
			)
			(placement
				(enabled no)
				(sheetname "")
			)
			(fill
				(thermal_gap 0.5)
				(thermal_bridge_width 0.5)
				(island_removal_mode 0)
			)
			(polygon
				(pts
					(xy 174.3456 -5.207) (xy 174.3456 -5.715) (xy 173.9646 -5.715) (xy 173.9646 -5.207)
				)
			)
		)
		(zone
			(layer "F.Cu")
			(hatch none 0.5)
			(connect_pads
				(clearance 0)
			)
			(min_thickness 0.25)
			(keepout
				(tracks not_allowed)
				(vias allowed)
				(pads allowed)
				(copperpour not_allowed)
				(footprints allowed)
			)
			(placement
				(enabled no)
				(sheetname "")
			)
			(fill
				(thermal_gap 0.5)
				(thermal_bridge_width 0.5)
				(island_removal_mode 0)
			)
			(polygon
				(pts
					(xy 174.3456 -5.207) (xy 174.3456 -5.715) (xy 173.9646 -5.715) (xy 173.9646 -5.207)
				)
			)
		)
	)
	(footprint ""
		(layer "F.Cu")
		(at 411.80893 -134.699248 180)
		(property "Reference" "R8B2"
			(at 0 0 180)
			(layer "F.SilkS")
			(hide yes)
			(effects
				(font
					(size 1.27 1.27)
				)
			)
		)
		(property "Value" ""
			(at 0 0 180)
			(layer "F.Fab")
			(effects
				(font
					(size 1.27 1.27)
				)
			)
		)
		(duplicate_pad_numbers_are_jumpers no)
		(fp_poly
			(pts
				(xy -0.2794 -0.1016) (xy 0.2794 -0.1016) (xy 0.2794 0.9906) (xy -0.2794 0.9906)
			)
			(stroke
				(width 0)
				(type default)
			)
			(fill no)
			(layer "F.CrtYd")
		)
		(fp_line
			(start 0.2794 0.9906)
			(end 0.2794 -0.1016)
			(stroke
				(width 0.1)
				(type default)
			)
			(layer "F.Fab")
		)
		(fp_line
			(start 0.2794 -0.1016)
			(end -0.2794 -0.1016)
			(stroke
				(width 0.1)
				(type default)
			)
			(layer "F.Fab")
		)
		(fp_line
			(start -0.2794 0.9906)
			(end 0.2794 0.9906)
			(stroke
				(width 0.1)
				(type default)
			)
			(layer "F.Fab")
		)
		(fp_line
			(start -0.2794 -0.1016)
			(end -0.2794 0.9906)
			(stroke
				(width 0.1)
				(type default)
			)
			(layer "F.Fab")
		)
		(pad "1" smd rect
			(at 0 0 180)
			(size 0.508 0.508)
			(layers "F.Cu" "F.Mask" "F.Paste")
			(net "XDP_TRST_N")
		)
		(pad "2" smd rect
			(at 0 0.889 180)
			(size 0.508 0.508)
			(layers "F.Cu" "F.Mask" "F.Paste")
			(net "GND")
		)
		(zone
			(layer "F.Cu")
			(hatch none 0.5)
			(connect_pads
				(clearance 0)
			)
			(min_thickness 0.25)
			(keepout
				(tracks not_allowed)
				(vias allowed)
				(pads allowed)
				(copperpour not_allowed)
				(footprints allowed)
			)
			(placement
				(enabled no)
				(sheetname "")
			)
			(fill
				(thermal_gap 0.5)
				(thermal_bridge_width 0.5)
				(island_removal_mode 0)
			)
			(polygon
				(pts
					(xy 412.06293 -135.334248) (xy 411.55493 -135.334248) (xy 411.55493 -134.953248) (xy 412.06293 -134.953248)
				)
			)
		)
		(zone
			(layer "F.Cu")
			(hatch none 0.5)
			(connect_pads
				(clearance 0)
			)
			(min_thickness 0.25)
			(keepout
				(tracks allowed)
				(vias not_allowed)
				(pads allowed)
				(copperpour not_allowed)
				(footprints allowed)
			)
			(placement
				(enabled no)
				(sheetname "")
			)
			(fill
				(thermal_gap 0.5)
				(thermal_bridge_width 0.5)
				(island_removal_mode 0)
			)
			(polygon
				(pts
					(xy 412.06293 -134.953248) (xy 411.55493 -134.953248) (xy 411.55493 -135.334248) (xy 412.06293 -135.334248)
				)
			)
		)
	)
)
